# T6G (Grand Teton) — schematic netlist excerpt (pin names and nets, part order shuffled) for the footprints in the layout excerpt that follows; sources: Cadence DE-HDL packaged netlist, KiCad conversion of 04192023_DAF0TMB3IC0_F0TG_MB_C_brd_V02_OCP.brd

R819  Q_RES  0 5% CHIP  pkg 0402LF  page 164 : A = UART_CPU0_LVC3_UART0_R_RX ; B = UART_CPU0_LVC3_UART0_RX
R1417  Q_RES  4.7K 5% CHIP  pkg 0201LF  page 342 : A = JTAG_TCK_RT_CPU1_P2 ; B = GND
PR492  Q_RES  1.5 1% EMPTY  pkg 0402LF  page 223 : A = SW_PVDDIO_P1_SW3_RC ; B = GND

(kicad_pcb
	(version 20260206)
	(generator "pcbnew")
	(generator_version "10.0")
	(general
		(thickness 1.6)
		(legacy_teardrops no)
	)
	(paper "A4")
	(title_block
		(title "04192023_DAF0TMB3IC0_F0TG_MB_C_brd_V02_OCP.brd")
		(comment 1 "Grand Teton / footprints 772-774 of 8354")
	)
	(layers
		(0 "F.Cu" signal "TOP")
		(4 "In1.Cu" signal "GND")
		(6 "In2.Cu" signal "IN1")
		(8 "In3.Cu" signal "GND1")
		(10 "In4.Cu" signal "IN2")
		(12 "In5.Cu" signal "GND2")
		(14 "In6.Cu" signal "IN3")
		(16 "In7.Cu" signal "GND3")
		(18 "In8.Cu" signal "VCC")
		(20 "In9.Cu" signal "VCC1")
		(22 "In10.Cu" signal "GND4")
		(24 "In11.Cu" signal "IN4")
		(26 "In12.Cu" signal "GND5")
		(28 "In13.Cu" signal "IN5")
		(30 "In14.Cu" signal "GND6")
		(32 "In15.Cu" signal "IN6")
		(34 "In16.Cu" signal "GND7")
		(2 "B.Cu" signal "BOTTOM")
		(9 "F.Adhes" user "F.Adhesive")
		(11 "B.Adhes" user "B.Adhesive")
		(13 "F.Paste" user "Package Geometry/Pastemask Top")
		(15 "B.Paste" user "Package Geometry/Pastemask Bottom")
		(5 "F.SilkS" user "Ref Des/Silkscreen Top")
		(7 "B.SilkS" user "Ref Des/Silkscreen Bottom")
		(1 "F.Mask" user "Board Geometry/Soldermask Top")
		(3 "B.Mask" user "Board Geometry/Soldermask Bottom")
		(17 "Dwgs.User" user "User.Drawings")
		(19 "Cmts.User" user "User.Comments")
		(21 "Eco1.User" user "User.Eco1")
		(23 "Eco2.User" user "User.Eco2")
		(25 "Edge.Cuts" user "Board Geometry/Outline")
		(27 "Margin" user)
		(31 "F.CrtYd" user "Package Geometry/Place Bound Top")
		(29 "B.CrtYd" user "Package Geometry/Place Bound Bottom")
		(35 "F.Fab" user "Ref Des/Assembly Top")
		(33 "B.Fab" user "Ref Des/Assembly Bottom")
	)
	(footprint ""
		(layer "F.Cu")
		(at 180.3908 -394.1318)
		(property "Reference" "R1417"
			(at 0 0 0)
			(layer "F.SilkS")
			(hide yes)
			(effects
				(font
					(size 1.27 1.27)
				)
			)
		)
		(property "Value" ""
			(at 0 0 0)
			(layer "F.Fab")
			(effects
				(font
					(size 1.27 1.27)
				)
			)
		)
		(duplicate_pad_numbers_are_jumpers no)
		(fp_line
			(start -0.32512 -0.175006)
			(end 0.32512 -0.175006)
			(stroke
				(width 0.1)
				(type default)
			)
			(layer "F.Fab")
		)
		(fp_line
			(start -0.32512 0.175006)
			(end -0.32512 -0.175006)
			(stroke
				(width 0.1)
				(type default)
			)
			(layer "F.Fab")
		)
		(fp_line
			(start 0.32512 -0.175006)
			(end 0.32512 0.175006)
			(stroke
				(width 0.1)
				(type default)
			)
			(layer "F.Fab")
		)
		(fp_line
			(start 0.32512 0.175006)
			(end -0.32512 0.175006)
			(stroke
				(width 0.1)
				(type default)
			)
			(layer "F.Fab")
		)
		(pad "1" smd rect
			(at -0.2667 0)
			(size 0.3048 0.381)
			(layers "F.Cu" "F.Mask" "F.Paste")
			(net "JTAG_TCK_RT_CPU1_P2")
		)
		(pad "2" smd rect
			(at 0.2667 0 180)
			(size 0.3048 0.381)
			(layers "F.Cu" "F.Mask" "F.Paste")
			(net "GND")
		)
	)
	(footprint ""
		(layer "F.Cu")
		(at 33.203896 -344.986864 90)
		(property "Reference" "PR492"
			(at 0 0 90)
			(layer "F.SilkS")
			(hide yes)
			(effects
				(font
					(size 1.27 1.27)
				)
			)
		)
		(property "Value" ""
			(at 0 0 90)
			(layer "F.Fab")
			(effects
				(font
					(size 1.27 1.27)
				)
			)
		)
		(duplicate_pad_numbers_are_jumpers no)
		(fp_line
			(start 0.7874 -0.4064)
			(end 0.7874 0.4064)
			(stroke
				(width 0.1524)
				(type default)
			)
			(layer "F.SilkS")
		)
		(fp_line
			(start -0.7874 -0.4064)
			(end 0.7874 -0.4064)
			(stroke
				(width 0.1524)
				(type default)
			)
			(layer "F.SilkS")
		)
		(fp_line
			(start 0.7874 0.4064)
			(end -0.7874 0.4064)
			(stroke
				(width 0.1524)
				(type default)
			)
			(layer "F.SilkS")
		)
		(fp_line
			(start -0.7874 0.4064)
			(end -0.7874 -0.4064)
			(stroke
				(width 0.1524)
				(type default)
			)
			(layer "F.SilkS")
		)
		(fp_line
			(start -0.12065 -0.305054)
			(end -0.12065 -0.2794)
			(stroke
				(width 0.1)
				(type default)
			)
			(layer "F.Fab")
		)
		(fp_line
			(start -0.67945 -0.305054)
			(end -0.12065 -0.305054)
			(stroke
				(width 0.1)
				(type default)
			)
			(layer "F.Fab")
		)
		(fp_line
			(start 0.67945 -0.3048)
			(end 0.67945 0.3048)
			(stroke
				(width 0.1)
				(type default)
			)
			(layer "F.Fab")
		)
		(fp_line
			(start 0.12065 -0.3048)
			(end 0.67945 -0.3048)
			(stroke
				(width 0.1)
				(type default)
			)
			(layer "F.Fab")
		)
		(fp_line
			(start 0.12065 -0.2794)
			(end 0.12065 -0.3048)
			(stroke
				(width 0.1)
				(type default)
			)
			(layer "F.Fab")
		)
		(fp_line
			(start -0.12065 -0.2794)
			(end 0.12065 -0.2794)
			(stroke
				(width 0.1)
				(type default)
			)
			(layer "F.Fab")
		)
		(fp_line
			(start 0.120396 0.2794)
			(end -0.12065 0.2794)
			(stroke
				(width 0.1)
				(type default)
			)
			(layer "F.Fab")
		)
		(fp_line
			(start -0.12065 0.2794)
			(end -0.12065 0.3048)
			(stroke
				(width 0.1)
				(type default)
			)
			(layer "F.Fab")
		)
		(fp_line
			(start 0.67945 0.3048)
			(end 0.120396 0.3048)
			(stroke
				(width 0.1)
				(type default)
			)
			(layer "F.Fab")
		)
		(fp_line
			(start 0.120396 0.3048)
			(end 0.120396 0.2794)
			(stroke
				(width 0.1)
				(type default)
			)
			(layer "F.Fab")
		)
		(fp_line
			(start -0.12065 0.3048)
			(end -0.67945 0.3048)
			(stroke
				(width 0.1)
				(type default)
			)
			(layer "F.Fab")
		)
		(fp_line
			(start -0.67945 0.3048)
			(end -0.67945 -0.305054)
			(stroke
				(width 0.1)
				(type default)
			)
			(layer "F.Fab")
		)
		(pad "1" smd circle
			(at -0.40005 0 90)
			(size 0 0)
			(layers "F.Cu" "F.Mask" "F.Paste")
			(net "SW_PVDDIO_P1_SW3_RC")
		)
		(pad "2" smd circle
			(at 0.40005 0 90)
			(size 0 0)
			(layers "F.Cu" "F.Mask" "F.Paste")
			(net "GND")
		)
	)
	(footprint ""
		(layer "F.Cu")
		(at 365.518446 -30.084522 -90)
		(property "Reference" "R819"
			(at 0 0 270)
			(layer "F.SilkS")
			(hide yes)
			(effects
				(font
					(size 1.27 1.27)
				)
			)
		)
		(property "Value" ""
			(at 0 0 270)
			(layer "F.Fab")
			(effects
				(font
					(size 1.27 1.27)
				)
			)
		)
		(duplicate_pad_numbers_are_jumpers no)
		(fp_line
			(start -0.7874 0.4064)
			(end -0.7874 -0.4064)
			(stroke
				(width 0.1524)
				(type default)
			)
			(layer "F.SilkS")
		)
		(fp_line
			(start 0.7874 0.4064)
			(end -0.7874 0.4064)
			(stroke
				(width 0.1524)
				(type default)
			)
			(layer "F.SilkS")
		)
		(fp_line
			(start -0.7874 -0.4064)
			(end 0.7874 -0.4064)
			(stroke
				(width 0.1524)
				(type default)
			)
			(layer "F.SilkS")
		)
		(fp_line
			(start 0.7874 -0.4064)
			(end 0.7874 0.4064)
			(stroke
				(width 0.1524)
				(type default)
			)
			(layer "F.SilkS")
		)
		(fp_line
			(start -0.67945 0.3048)
			(end -0.67945 -0.305054)
			(stroke
				(width 0.1)
				(type default)
			)
			(layer "F.Fab")
		)
		(fp_line
			(start -0.12065 0.3048)
			(end -0.67945 0.3048)
			(stroke
				(width 0.1)
				(type default)
			)
			(layer "F.Fab")
		)
		(fp_line
			(start 0.120396 0.3048)
			(end 0.120396 0.2794)
			(stroke
				(width 0.1)
				(type default)
			)
			(layer "F.Fab")
		)
		(fp_line
			(start 0.67945 0.3048)
			(end 0.120396 0.3048)
			(stroke
				(width 0.1)
				(type default)
			)
			(layer "F.Fab")
		)
		(fp_line
			(start -0.12065 0.2794)
			(end -0.12065 0.3048)
			(stroke
				(width 0.1)
				(type default)
			)
			(layer "F.Fab")
		)
		(fp_line
			(start 0.120396 0.2794)
			(end -0.12065 0.2794)
			(stroke
				(width 0.1)
				(type default)
			)
			(layer "F.Fab")
		)
		(fp_line
			(start -0.12065 -0.2794)
			(end 0.12065 -0.2794)
			(stroke
				(width 0.1)
				(type default)
			)
			(layer "F.Fab")
		)
		(fp_line
			(start 0.12065 -0.2794)
			(end 0.12065 -0.3048)
			(stroke
				(width 0.1)
				(type default)
			)
			(layer "F.Fab")
		)
		(fp_line
			(start 0.12065 -0.3048)
			(end 0.67945 -0.3048)
			(stroke
				(width 0.1)
				(type default)
			)
			(layer "F.Fab")
		)
		(fp_line
			(start 0.67945 -0.3048)
			(end 0.67945 0.3048)
			(stroke
				(width 0.1)
				(type default)
			)
			(layer "F.Fab")
		)
		(fp_line
			(start -0.67945 -0.305054)
			(end -0.12065 -0.305054)
			(stroke
				(width 0.1)
				(type default)
			)
			(layer "F.Fab")
		)
		(fp_line
			(start -0.12065 -0.305054)
			(end -0.12065 -0.2794)
			(stroke
				(width 0.1)
				(type default)
			)
			(layer "F.Fab")
		)
		(pad "1" smd circle
			(at -0.40005 0 270)
			(size 0 0)
			(layers "F.Cu" "F.Mask" "F.Paste")
			(net "UART_CPU0_LVC3_UART0_R_RX")
		)
		(pad "2" smd circle
			(at 0.40005 0 270)
			(size 0 0)
			(layers "F.Cu" "F.Mask" "F.Paste")
			(net "UART_CPU0_LVC3_UART0_RX")
		)
	)
)
